# BASEBOARD_FAB2 (Tioga Pass) — schematic netlist excerpt (pin names and nets, part order shuffled) for the footprints in the layout excerpt that follows; sources: Cadence DE-HDL packaged netlist, KiCad conversion of Wiwynn_Tioga_Pass_MB.brd

R25W65  RES  100.0K 1% CHIP  pkg 0402  page 145 : A = P2E_SSB_BMC_TX_C_DN ; B = GND
C25W6  CAP  1.0UF 16V 10% X6S  pkg 0402  page 151 : A = P1V2_AUX_BMC ; B = GND
C2A13  CAP_A  47UF 4V 20% X5R  pkg 0603V  page 228 : A = PVDDQ_KLM ; B = GND

(kicad_pcb
	(version 20260206)
	(generator "pcbnew")
	(generator_version "10.0")
	(general
		(thickness 1.6)
		(legacy_teardrops no)
	)
	(paper "A4")
	(title_block
		(title "Wiwynn_Tioga_Pass_MB.brd")
		(comment 1 "Tioga Pass / footprints 553-555 of 4770")
	)
	(layers
		(0 "F.Cu" signal "TOP")
		(4 "In1.Cu" signal "L2GND")
		(6 "In2.Cu" signal "L3")
		(8 "In3.Cu" signal "L4GND")
		(10 "In4.Cu" signal "L5")
		(12 "In5.Cu" signal "L6GND")
		(14 "In6.Cu" signal "L7VCC")
		(16 "In7.Cu" signal "L8VCC")
		(18 "In8.Cu" signal "L9GND")
		(20 "In9.Cu" signal "L10")
		(22 "In10.Cu" signal "L11GND")
		(24 "In11.Cu" signal "L12")
		(26 "In12.Cu" signal "L13GND")
		(2 "B.Cu" signal "BOTTOM")
		(9 "F.Adhes" user "F.Adhesive")
		(11 "B.Adhes" user "B.Adhesive")
		(13 "F.Paste" user "Package Geometry/Pastemask Top")
		(15 "B.Paste" user "Package Geometry/Pastemask Bottom")
		(5 "F.SilkS" user "Ref Des/Silkscreen Top")
		(7 "B.SilkS" user "Ref Des/Silkscreen Bottom")
		(1 "F.Mask" user "Board Geometry/Soldermask Top")
		(3 "B.Mask" user "Board Geometry/Soldermask Bottom")
		(17 "Dwgs.User" user "User.Drawings")
		(19 "Cmts.User" user "User.Comments")
		(21 "Eco1.User" user "User.Eco1")
		(23 "Eco2.User" user "User.Eco2")
		(25 "Edge.Cuts" user "Board Geometry/Outline")
		(27 "Margin" user)
		(31 "F.CrtYd" user "Package Geometry/Place Bound Top")
		(29 "B.CrtYd" user "Package Geometry/Place Bound Bottom")
		(35 "F.Fab" user "Ref Des/Assembly Top")
		(33 "B.Fab" user "Ref Des/Assembly Bottom")
	)
	(footprint ""
		(layer "F.Cu")
		(at 447.301366 -28.33116 90)
		(property "Reference" "C25W6"
			(at -0.8382 -0.67818 90)
			(unlocked yes)
			(layer "F.SilkS")
			(effects
				(font
					(size 0.4064 0.254)
					(thickness 0.1524)
				)
				(justify left)
			)
		)
		(property "Value" ""
			(at 0 0 90)
			(layer "F.Fab")
			(effects
				(font
					(size 1.27 1.27)
				)
			)
		)
		(duplicate_pad_numbers_are_jumpers no)
		(fp_poly
			(pts
				(xy 0.3048 -0.1016) (xy 0.3048 0.9906) (xy -0.3048 0.9906) (xy -0.3048 -0.1016)
			)
			(stroke
				(width 0)
				(type default)
			)
			(fill no)
			(layer "F.CrtYd")
		)
		(fp_line
			(start 0.3048 -0.1016)
			(end -0.3048 -0.1016)
			(stroke
				(width 0.1)
				(type default)
			)
			(layer "F.Fab")
		)
		(fp_line
			(start -0.3048 -0.1016)
			(end -0.3048 0.9906)
			(stroke
				(width 0.1)
				(type default)
			)
			(layer "F.Fab")
		)
		(fp_line
			(start 0.3048 0.9906)
			(end 0.3048 -0.1016)
			(stroke
				(width 0.1)
				(type default)
			)
			(layer "F.Fab")
		)
		(fp_line
			(start -0.3048 0.9906)
			(end 0.3048 0.9906)
			(stroke
				(width 0.1)
				(type default)
			)
			(layer "F.Fab")
		)
		(pad "1" smd rect
			(at 0 0 90)
			(size 0.508 0.508)
			(layers "F.Cu" "F.Mask" "F.Paste")
			(net "P1V2_AUX_BMC")
		)
		(pad "2" smd rect
			(at 0 0.889 90)
			(size 0.508 0.508)
			(layers "F.Cu" "F.Mask" "F.Paste")
			(net "GND")
		)
		(zone
			(layer "F.Cu")
			(hatch none 0.5)
			(connect_pads
				(clearance 0)
			)
			(min_thickness 0.25)
			(keepout
				(tracks allowed)
				(vias not_allowed)
				(pads allowed)
				(copperpour not_allowed)
				(footprints allowed)
			)
			(placement
				(enabled no)
				(sheetname "")
			)
			(fill
				(thermal_gap 0.5)
				(thermal_bridge_width 0.5)
				(island_removal_mode 0)
			)
			(polygon
				(pts
					(xy 447.555366 -28.07716) (xy 447.555366 -28.58516) (xy 447.936366 -28.58516) (xy 447.936366 -28.07716)
				)
			)
		)
		(zone
			(layer "F.Cu")
			(hatch none 0.5)
			(connect_pads
				(clearance 0)
			)
			(min_thickness 0.25)
			(keepout
				(tracks not_allowed)
				(vias allowed)
				(pads allowed)
				(copperpour not_allowed)
				(footprints allowed)
			)
			(placement
				(enabled no)
				(sheetname "")
			)
			(fill
				(thermal_gap 0.5)
				(thermal_bridge_width 0.5)
				(island_removal_mode 0)
			)
			(polygon
				(pts
					(xy 447.936366 -28.07716) (xy 447.936366 -28.58516) (xy 447.555366 -28.58516) (xy 447.555366 -28.07716)
				)
			)
		)
	)
	(footprint ""
		(layer "F.Cu")
		(at 93.139768 -140.208 -90)
		(property "Reference" "C2A13"
			(at 1.848866 0.752348 270)
			(unlocked yes)
			(layer "F.SilkS")
			(effects
				(font
					(size 1.27 0.9652)
					(thickness 0.1524)
				)
			)
		)
		(property "Value" ""
			(at 0 0 270)
			(layer "F.Fab")
			(effects
				(font
					(size 1.27 1.27)
				)
			)
		)
		(duplicate_pad_numbers_are_jumpers no)
		(fp_rect
			(start -0.500126 1.598422)
			(end 0.500126 -0.201422)
			(stroke
				(width 0)
				(type default)
			)
			(fill no)
			(layer "F.CrtYd")
		)
		(fp_line
			(start -0.500126 1.598422)
			(end -0.500126 -0.201422)
			(stroke
				(width 0.1)
				(type default)
			)
			(layer "F.Fab")
		)
		(fp_line
			(start 0.500126 1.598422)
			(end -0.500126 1.598422)
			(stroke
				(width 0.1)
				(type default)
			)
			(layer "F.Fab")
		)
		(fp_line
			(start -0.500126 -0.201422)
			(end 0.500126 -0.201422)
			(stroke
				(width 0.1)
				(type default)
			)
			(layer "F.Fab")
		)
		(fp_line
			(start 0.500126 -0.201422)
			(end 0.500126 1.598422)
			(stroke
				(width 0.1)
				(type default)
			)
			(layer "F.Fab")
		)
		(pad "1" smd rect
			(at 0 0 180)
			(size 0.889 0.9906)
			(layers "F.Cu" "F.Mask" "F.Paste")
			(net "PVDDQ_KLM")
		)
		(pad "2" smd rect
			(at 0 1.397 180)
			(size 0.889 0.9906)
			(layers "F.Cu" "F.Mask" "F.Paste")
			(net "GND")
		)
		(zone
			(layer "F.Cu")
			(hatch none 0.5)
			(connect_pads
				(clearance 0)
			)
			(min_thickness 0.25)
			(keepout
				(tracks allowed)
				(vias not_allowed)
				(pads allowed)
				(copperpour not_allowed)
				(footprints allowed)
			)
			(placement
				(enabled no)
				(sheetname "")
			)
			(fill
				(thermal_gap 0.5)
				(thermal_bridge_width 0.5)
				(island_removal_mode 0)
			)
			(polygon
				(pts
					(xy 92.187268 -140.7033) (xy 92.187268 -139.7127) (xy 92.695268 -139.7127) (xy 92.695268 -140.7033)
				)
			)
		)
		(zone
			(layer "F.Cu")
			(hatch none 0.5)
			(connect_pads
				(clearance 0)
			)
			(min_thickness 0.25)
			(keepout
				(tracks not_allowed)
				(vias allowed)
				(pads allowed)
				(copperpour not_allowed)
				(footprints allowed)
			)
			(placement
				(enabled no)
				(sheetname "")
			)
			(fill
				(thermal_gap 0.5)
				(thermal_bridge_width 0.5)
				(island_removal_mode 0)
			)
			(polygon
				(pts
					(xy 92.187268 -140.7033) (xy 92.187268 -139.7127) (xy 92.695268 -139.7127) (xy 92.695268 -140.7033)
				)
			)
		)
	)
	(footprint ""
		(layer "F.Cu")
		(at 415.749994 -47.828962 180)
		(property "Reference" "R25W65"
			(at -0.8382 -0.67818 180)
			(unlocked yes)
			(layer "F.SilkS")
			(effects
				(font
					(size 0.4064 0.254)
					(thickness 0.1524)
				)
				(justify left)
			)
		)
		(property "Value" ""
			(at 0 0 180)
			(layer "F.Fab")
			(effects
				(font
					(size 1.27 1.27)
				)
			)
		)
		(duplicate_pad_numbers_are_jumpers no)
		(fp_poly
			(pts
				(xy -0.2794 -0.1016) (xy 0.2794 -0.1016) (xy 0.2794 0.9906) (xy -0.2794 0.9906)
			)
			(stroke
				(width 0)
				(type default)
			)
			(fill no)
			(layer "F.CrtYd")
		)
		(fp_line
			(start 0.2794 0.9906)
			(end 0.2794 -0.1016)
			(stroke
				(width 0.1)
				(type default)
			)
			(layer "F.Fab")
		)
		(fp_line
			(start 0.2794 -0.1016)
			(end -0.2794 -0.1016)
			(stroke
				(width 0.1)
				(type default)
			)
			(layer "F.Fab")
		)
		(fp_line
			(start -0.2794 0.9906)
			(end 0.2794 0.9906)
			(stroke
				(width 0.1)
				(type default)
			)
			(layer "F.Fab")
		)
		(fp_line
			(start -0.2794 -0.1016)
			(end -0.2794 0.9906)
			(stroke
				(width 0.1)
				(type default)
			)
			(layer "F.Fab")
		)
		(pad "1" smd rect
			(at 0 0 180)
			(size 0.508 0.508)
			(layers "F.Cu" "F.Mask" "F.Paste")
			(net "P2E_SSB_BMC_TX_C_DN")
		)
		(pad "2" smd rect
			(at 0 0.889 180)
			(size 0.508 0.508)
			(layers "F.Cu" "F.Mask" "F.Paste")
			(net "GND")
		)
		(zone
			(layer "F.Cu")
			(hatch none 0.5)
			(connect_pads
				(clearance 0)
			)
			(min_thickness 0.25)
			(keepout
				(tracks not_allowed)
				(vias allowed)
				(pads allowed)
				(copperpour not_allowed)
				(footprints allowed)
			)
			(placement
				(enabled no)
				(sheetname "")
			)
			(fill
				(thermal_gap 0.5)
				(thermal_bridge_width 0.5)
				(island_removal_mode 0)
			)
			(polygon
				(pts
					(xy 416.003994 -48.463962) (xy 415.495994 -48.463962) (xy 415.495994 -48.082962) (xy 416.003994 -48.082962)
				)
			)
		)
		(zone
			(layer "F.Cu")
			(hatch none 0.5)
			(connect_pads
				(clearance 0)
			)
			(min_thickness 0.25)
			(keepout
				(tracks allowed)
				(vias not_allowed)
				(pads allowed)
				(copperpour not_allowed)
				(footprints allowed)
			)
			(placement
				(enabled no)
				(sheetname "")
			)
			(fill
				(thermal_gap 0.5)
				(thermal_bridge_width 0.5)
				(island_removal_mode 0)
			)
			(polygon
				(pts
					(xy 416.003994 -48.082962) (xy 415.495994 -48.082962) (xy 415.495994 -48.463962) (xy 416.003994 -48.463962)
				)
			)
		)
	)
)
